(kicad_pcb
	(version 20241229)
	(generator "pcbnew")
	(generator_version "9.0")
	(general
		(thickness 1.599998)
		(legacy_teardrops no)
	)
	(paper "A4")
	(title_block
		(date "2023-02-12")
		(rev "1.1.5")
		(comment 9 "footprints 17-23 of 473")
	)
	(layers
		(0 "F.Cu" signal)
		(4 "In1.Cu" power "In1.GND")
		(6 "In2.Cu" signal)
		(8 "In3.Cu" power "In3.GND")
		(10 "In4.Cu" power "In4.VCC")
		(12 "In5.Cu" signal)
		(14 "In6.Cu" power "In6.VCC")
		(2 "B.Cu" signal)
		(9 "F.Adhes" user "F.Adhesive")
		(11 "B.Adhes" user "B.Adhesive")
		(13 "F.Paste" user)
		(15 "B.Paste" user)
		(5 "F.SilkS" user "F.Silkscreen")
		(7 "B.SilkS" user "B.Silkscreen")
		(1 "F.Mask" user)
		(3 "B.Mask" user)
		(17 "Dwgs.User" user "User.Drawings")
		(19 "Cmts.User" user "User.Comments")
		(21 "Eco1.User" user "User.Eco1")
		(23 "Eco2.User" user "User.Eco2")
		(25 "Edge.Cuts" user)
		(27 "Margin" user)
		(31 "F.CrtYd" user "F.Courtyard")
		(29 "B.CrtYd" user "B.Courtyard")
		(35 "F.Fab" user)
		(33 "B.Fab" user)
	)
	(footprint "antmicro-footprints:R_0402_1005Metric"
		(layer "F.Cu")
		(at 141.411328 100.246157 90)
		(descr "Resistor SMD 0402")
		(tags "resistor SMD 0402")
		(property "Reference" "R23"
			(at 0.746157 0.388672 90)
			(layer "F.SilkS")
			(effects
				(font
					(size 0.7 0.7)
					(thickness 0.15)
				)
				(justify left bottom)
			)
		)
		(property "Value" "R_22R_0402"
			(at 0 1.4 90)
			(layer "F.Fab")
			(effects
				(font
					(size 0.7 0.7)
					(thickness 0.15)
				)
				(justify left bottom)
			)
		)
		(property "Description" "22R resistor in 0402 package with 1% tolerance"
			(at 0 0 90)
			(layer "F.Fab")
			(hide yes)
			(effects
				(font
					(size 1.27 1.27)
					(thickness 0.15)
				)
			)
		)
		(property "Author" "Antmicro"
			(at 241.657485 -41.165171 0)
			(layer "F.Fab")
			(hide yes)
			(effects
				(font
					(size 1 1)
					(thickness 0.15)
				)
			)
		)
		(property "License" "Apache-2.0"
			(at 241.657485 -41.165171 0)
			(layer "F.Fab")
			(hide yes)
			(effects
				(font
					(size 1 1)
					(thickness 0.15)
				)
			)
		)
		(property "MPN" "CR0402-FX-22R0GLF"
			(at 241.657485 -41.165171 0)
			(layer "F.Fab")
			(hide yes)
			(effects
				(font
					(size 1 1)
					(thickness 0.15)
				)
			)
		)
		(property "Manufacturer" "Bourns"
			(at 241.657485 -41.165171 0)
			(layer "F.Fab")
			(hide yes)
			(effects
				(font
					(size 1 1)
					(thickness 0.15)
				)
			)
		)
		(property "Tolerance" "1%"
			(at 241.657485 -41.165171 0)
			(layer "F.Fab")
			(hide yes)
			(effects
				(font
					(size 1 1)
					(thickness 0.15)
				)
			)
		)
		(property "Val" "22R"
			(at 241.657485 -41.165171 0)
			(layer "F.Fab")
			(hide yes)
			(effects
				(font
					(size 1 1)
					(thickness 0.15)
				)
			)
		)
		(sheetname "Interfaces")
		(sheetfile "interfaces.kicad_sch")
		(attr smd)
		(fp_rect
			(start -0.93 -0.47)
			(end 0.93 0.47)
			(stroke
				(width 0.05)
				(type solid)
			)
			(fill no)
			(layer "F.CrtYd")
		)
		(fp_rect
			(start -0.5 -0.25)
			(end 0.5 0.25)
			(stroke
				(width 0.15)
				(type solid)
			)
			(fill no)
			(layer "F.Fab")
		)
		(pad "1" smd roundrect
			(at -0.485 0 90)
			(size 0.59 0.64)
			(layers "F.Cu" "F.Mask" "F.Paste")
			(roundrect_rratio 0.25)
			(net 252 "Net-(U4-CDBUS1)")
			(pintype "passive")
		)
		(pad "2" smd roundrect
			(at 0.485 0 90)
			(size 0.59 0.64)
			(layers "F.Cu" "F.Mask" "F.Paste")
			(roundrect_rratio 0.25)
			(net 453 "UART0_TX")
			(pintype "passive")
		)
	)
	(footprint "antmicro-footprints:R_0402_1005Metric"
		(layer "F.Cu")
		(at 133.911328 102.621157 180)
		(descr "Resistor SMD 0402")
		(tags "resistor SMD 0402")
		(property "Reference" "R24"
			(at -0.688672 -0.378843 180)
			(layer "F.SilkS")
			(effects
				(font
					(size 0.7 0.7)
					(thickness 0.15)
				)
				(justify left bottom)
			)
		)
		(property "Value" "R_22R_0402"
			(at 0 1.4 180)
			(layer "F.Fab")
			(effects
				(font
					(size 0.7 0.7)
					(thickness 0.15)
				)
				(justify left bottom)
			)
		)
		(property "Description" "22R resistor in 0402 package with 1% tolerance"
			(at 0 0 180)
			(layer "F.Fab")
			(hide yes)
			(effects
				(font
					(size 1.27 1.27)
					(thickness 0.15)
				)
			)
		)
		(property "Author" "Antmicro"
			(at 267.822656 205.242314 0)
			(layer "F.Fab")
			(hide yes)
			(effects
				(font
					(size 1 1)
					(thickness 0.15)
				)
			)
		)
		(property "License" "Apache-2.0"
			(at 267.822656 205.242314 0)
			(layer "F.Fab")
			(hide yes)
			(effects
				(font
					(size 1 1)
					(thickness 0.15)
				)
			)
		)
		(property "MPN" "CR0402-FX-22R0GLF"
			(at 267.822656 205.242314 0)
			(layer "F.Fab")
			(hide yes)
			(effects
				(font
					(size 1 1)
					(thickness 0.15)
				)
			)
		)
		(property "Manufacturer" "Bourns"
			(at 267.822656 205.242314 0)
			(layer "F.Fab")
			(hide yes)
			(effects
				(font
					(size 1 1)
					(thickness 0.15)
				)
			)
		)
		(property "Tolerance" "1%"
			(at 267.822656 205.242314 0)
			(layer "F.Fab")
			(hide yes)
			(effects
				(font
					(size 1 1)
					(thickness 0.15)
				)
			)
		)
		(property "Val" "22R"
			(at 267.822656 205.242314 0)
			(layer "F.Fab")
			(hide yes)
			(effects
				(font
					(size 1 1)
					(thickness 0.15)
				)
			)
		)
		(sheetname "Interfaces")
		(sheetfile "interfaces.kicad_sch")
		(attr smd)
		(fp_rect
			(start -0.93 -0.47)
			(end 0.93 0.47)
			(stroke
				(width 0.05)
				(type solid)
			)
			(fill no)
			(layer "F.CrtYd")
		)
		(fp_rect
			(start -0.5 -0.25)
			(end 0.5 0.25)
			(stroke
				(width 0.15)
				(type solid)
			)
			(fill no)
			(layer "F.Fab")
		)
		(pad "1" smd roundrect
			(at -0.485 0 180)
			(size 0.59 0.64)
			(layers "F.Cu" "F.Mask" "F.Paste")
			(roundrect_rratio 0.25)
			(net 253 "Net-(U4-DDBUS0)")
			(pintype "passive")
		)
		(pad "2" smd roundrect
			(at 0.485 0 180)
			(size 0.59 0.64)
			(layers "F.Cu" "F.Mask" "F.Paste")
			(roundrect_rratio 0.25)
			(net 455 "UART1_RX")
			(pintype "passive")
		)
	)
	(footprint "antmicro-footprints:R_0402_1005Metric"
		(layer "F.Cu")
		(at 133.911328 105.871157 180)
		(descr "Resistor SMD 0402")
		(tags "resistor SMD 0402")
		(property "Reference" "R25"
			(at 2.911328 -0.428843 180)
			(layer "F.SilkS")
			(effects
				(font
					(size 0.7 0.7)
					(thickness 0.15)
				)
				(justify left bottom)
			)
		)
		(property "Value" "R_22R_0402"
			(at 0 1.4 180)
			(layer "F.Fab")
			(effects
				(font
					(size 0.7 0.7)
					(thickness 0.15)
				)
				(justify left bottom)
			)
		)
		(property "Description" "22R resistor in 0402 package with 1% tolerance"
			(at 0 0 180)
			(layer "F.Fab")
			(hide yes)
			(effects
				(font
					(size 1.27 1.27)
					(thickness 0.15)
				)
			)
		)
		(property "Author" "Antmicro"
			(at 267.822656 211.742314 0)
			(layer "F.Fab")
			(hide yes)
			(effects
				(font
					(size 1 1)
					(thickness 0.15)
				)
			)
		)
		(property "License" "Apache-2.0"
			(at 267.822656 211.742314 0)
			(layer "F.Fab")
			(hide yes)
			(effects
				(font
					(size 1 1)
					(thickness 0.15)
				)
			)
		)
		(property "MPN" "CR0402-FX-22R0GLF"
			(at 267.822656 211.742314 0)
			(layer "F.Fab")
			(hide yes)
			(effects
				(font
					(size 1 1)
					(thickness 0.15)
				)
			)
		)
		(property "Manufacturer" "Bourns"
			(at 267.822656 211.742314 0)
			(layer "F.Fab")
			(hide yes)
			(effects
				(font
					(size 1 1)
					(thickness 0.15)
				)
			)
		)
		(property "Tolerance" "1%"
			(at 267.822656 211.742314 0)
			(layer "F.Fab")
			(hide yes)
			(effects
				(font
					(size 1 1)
					(thickness 0.15)
				)
			)
		)
		(property "Val" "22R"
			(at 267.822656 211.742314 0)
			(layer "F.Fab")
			(hide yes)
			(effects
				(font
					(size 1 1)
					(thickness 0.15)
				)
			)
		)
		(sheetname "Interfaces")
		(sheetfile "interfaces.kicad_sch")
		(attr smd)
		(fp_rect
			(start -0.93 -0.47)
			(end 0.93 0.47)
			(stroke
				(width 0.05)
				(type solid)
			)
			(fill no)
			(layer "F.CrtYd")
		)
		(fp_rect
			(start -0.5 -0.25)
			(end 0.5 0.25)
			(stroke
				(width 0.15)
				(type solid)
			)
			(fill no)
			(layer "F.Fab")
		)
		(pad "1" smd roundrect
			(at -0.485 0 180)
			(size 0.59 0.64)
			(layers "F.Cu" "F.Mask" "F.Paste")
			(roundrect_rratio 0.25)
			(net 254 "Net-(U4-DDBUS1)")
			(pintype "passive")
		)
		(pad "2" smd roundrect
			(at 0.485 0 180)
			(size 0.59 0.64)
			(layers "F.Cu" "F.Mask" "F.Paste")
			(roundrect_rratio 0.25)
			(net 457 "UART1_TX")
			(pintype "passive")
		)
	)
	(footprint "antmicro-footprints:C_0402_1005Metric"
		(layer "F.Cu")
		(at 115.3492 113.622157 180)
		(descr "Capacitor SMD 0402")
		(tags "capacitor SMD 0402")
		(property "Reference" "C132"
			(at 1.8492 1.522157 180)
			(layer "F.SilkS")
			(effects
				(font
					(size 0.7 0.7)
					(thickness 0.15)
				)
				(justify left bottom)
			)
		)
		(property "Value" "C_100n_6V3_0402"
			(at 0 1.4 180)
			(layer "F.Fab")
			(effects
				(font
					(size 0.7 0.7)
					(thickness 0.15)
				)
				(justify left bottom)
			)
		)
		(property "Description" " "
			(at 0 0 180)
			(layer "F.Fab")
			(hide yes)
			(effects
				(font
					(size 1.27 1.27)
					(thickness 0.15)
				)
			)
		)
		(property "Author" "Antmicro"
			(at 230.6984 227.244314 0)
			(layer "F.Fab")
			(hide yes)
			(effects
				(font
					(size 1 1)
					(thickness 0.15)
				)
			)
		)
		(property "Dielectric" ""
			(at 230.6984 227.244314 0)
			(layer "F.Fab")
			(hide yes)
			(effects
				(font
					(size 1 1)
					(thickness 0.15)
				)
			)
		)
		(property "License" "Apache-2.0"
			(at 230.6984 227.244314 0)
			(layer "F.Fab")
			(hide yes)
			(effects
				(font
					(size 1 1)
					(thickness 0.15)
				)
			)
		)
		(property "MPN" "0402X104K6R3CT"
			(at 230.6984 227.244314 0)
			(layer "F.Fab")
			(hide yes)
			(effects
				(font
					(size 1 1)
					(thickness 0.15)
				)
			)
		)
		(property "Manufacturer" "Walsin"
			(at 230.6984 227.244314 0)
			(layer "F.Fab")
			(hide yes)
			(effects
				(font
					(size 1 1)
					(thickness 0.15)
				)
			)
		)
		(property "Val" "100n"
			(at 230.6984 227.244314 0)
			(layer "F.Fab")
			(hide yes)
			(effects
				(font
					(size 1 1)
					(thickness 0.15)
				)
			)
		)
		(property "Voltage" ""
			(at 230.6984 227.244314 0)
			(layer "F.Fab")
			(hide yes)
			(effects
				(font
					(size 1 1)
					(thickness 0.15)
				)
			)
		)
		(sheetname "Supply")
		(sheetfile "supply.kicad_sch")
		(attr smd)
		(fp_rect
			(start -0.94 -0.47)
			(end 0.94 0.47)
			(stroke
				(width 0.05)
				(type solid)
			)
			(fill no)
			(layer "F.CrtYd")
		)
		(fp_rect
			(start -0.499 -0.249)
			(end 0.499 0.249)
			(stroke
				(width 0.15)
				(type solid)
			)
			(fill no)
			(layer "F.Fab")
		)
		(pad "1" smd roundrect
			(at -0.484 0 180)
			(size 0.59 0.64)
			(layers "F.Cu" "F.Mask" "F.Paste")
			(roundrect_rratio 0.25)
			(net 42 "Net-(IC2-SW)")
			(pintype "passive")
		)
		(pad "2" smd roundrect
			(at 0.484 0 180)
			(size 0.59 0.64)
			(layers "F.Cu" "F.Mask" "F.Paste")
			(roundrect_rratio 0.25)
			(net 43 "Net-(IC2-BOOT)")
			(pintype "passive")
		)
	)
	(footprint "antmicro-footprints:R_0402_1005Metric"
		(layer "F.Cu")
		(at 110.235528 117.872157)
		(descr "Resistor SMD 0402")
		(tags "resistor SMD 0402")
		(property "Reference" "R96"
			(at -2.935528 -0.7 0)
			(layer "F.SilkS")
			(effects
				(font
					(size 0.7 0.7)
					(thickness 0.15)
				)
				(justify left bottom)
			)
		)
		(property "Value" "R_243k_0402"
			(at 0 1.4 0)
			(layer "F.Fab")
			(effects
				(font
					(size 0.7 0.7)
					(thickness 0.15)
				)
				(justify left bottom)
			)
		)
		(property "Description" "243k resistor in 0402 package with 1% tolerance"
			(at 0 0 0)
			(layer "F.Fab")
			(hide yes)
			(effects
				(font
					(size 1.27 1.27)
					(thickness 0.15)
				)
			)
		)
		(property "Author" "Antmicro"
			(at 0 0 0)
			(layer "F.Fab")
			(hide yes)
			(effects
				(font
					(size 1 1)
					(thickness 0.15)
				)
			)
		)
		(property "License" "Apache-2.0"
			(at 0 0 0)
			(layer "F.Fab")
			(hide yes)
			(effects
				(font
					(size 1 1)
					(thickness 0.15)
				)
			)
		)
		(property "MPN" "CR0402-FX-2433GLF"
			(at 0 0 0)
			(layer "F.Fab")
			(hide yes)
			(effects
				(font
					(size 1 1)
					(thickness 0.15)
				)
			)
		)
		(property "Manufacturer" "Bourns"
			(at 0 0 0)
			(layer "F.Fab")
			(hide yes)
			(effects
				(font
					(size 1 1)
					(thickness 0.15)
				)
			)
		)
		(property "Tolerance" "1%"
			(at 0 0 0)
			(layer "F.Fab")
			(hide yes)
			(effects
				(font
					(size 1 1)
					(thickness 0.15)
				)
			)
		)
		(property "Val" "243k"
			(at 0 0 0)
			(layer "F.Fab")
			(hide yes)
			(effects
				(font
					(size 1 1)
					(thickness 0.15)
				)
			)
		)
		(sheetname "Supply")
		(sheetfile "supply.kicad_sch")
		(attr smd)
		(fp_rect
			(start -0.93 -0.47)
			(end 0.93 0.47)
			(stroke
				(width 0.05)
				(type solid)
			)
			(fill no)
			(layer "F.CrtYd")
		)
		(fp_rect
			(start -0.5 -0.25)
			(end 0.5 0.25)
			(stroke
				(width 0.15)
				(type solid)
			)
			(fill no)
			(layer "F.Fab")
		)
		(pad "1" smd roundrect
			(at -0.485 0)
			(size 0.59 0.64)
			(layers "F.Cu" "F.Mask" "F.Paste")
			(roundrect_rratio 0.25)
			(net 5 "GND")
			(pintype "passive")
		)
		(pad "2" smd roundrect
			(at 0.485 0)
			(size 0.59 0.64)
			(layers "F.Cu" "F.Mask" "F.Paste")
			(roundrect_rratio 0.25)
			(net 77 "Net-(IC2-RT{slash}CLK)")
			(pintype "passive")
		)
	)
	(footprint "antmicro-footprints:R_0402_1005Metric"
		(layer "F.Cu")
		(at 118.852872 118.975 180)
		(descr "Resistor SMD 0402")
		(tags "resistor SMD 0402")
		(property "Reference" "R103"
			(at 0.952872 -2.225 180)
			(layer "F.SilkS")
			(effects
				(font
					(size 0.7 0.7)
					(thickness 0.15)
				)
				(justify left bottom)
			)
		)
		(property "Value" "R_49R9_0402"
			(at 0 1.4 180)
			(layer "F.Fab")
			(effects
				(font
					(size 0.7 0.7)
					(thickness 0.15)
				)
				(justify left bottom)
			)
		)
		(property "Description" "49R9 resistor in 0402 package with 1% tolerance"
			(at 0 0 180)
			(layer "F.Fab")
			(hide yes)
			(effects
				(font
					(size 1.27 1.27)
					(thickness 0.15)
				)
			)
		)
		(property "Author" "Antmicro"
			(at 237.705744 237.95 0)
			(layer "F.Fab")
			(hide yes)
			(effects
				(font
					(size 1 1)
					(thickness 0.15)
				)
			)
		)
		(property "License" "Apache-2.0"
			(at 237.705744 237.95 0)
			(layer "F.Fab")
			(hide yes)
			(effects
				(font
					(size 1 1)
					(thickness 0.15)
				)
			)
		)
		(property "MPN" "CR0402-FX-49R9GLF"
			(at 237.705744 237.95 0)
			(layer "F.Fab")
			(hide yes)
			(effects
				(font
					(size 1 1)
					(thickness 0.15)
				)
			)
		)
		(property "Manufacturer" "Bourns"
			(at 237.705744 237.95 0)
			(layer "F.Fab")
			(hide yes)
			(effects
				(font
					(size 1 1)
					(thickness 0.15)
				)
			)
		)
		(property "Tolerance" "1%"
			(at 237.705744 237.95 0)
			(layer "F.Fab")
			(hide yes)
			(effects
				(font
					(size 1 1)
					(thickness 0.15)
				)
			)
		)
		(property "Val" "49R9"
			(at 237.705744 237.95 0)
			(layer "F.Fab")
			(hide yes)
			(effects
				(font
					(size 1 1)
					(thickness 0.15)
				)
			)
		)
		(sheetname "Supply")
		(sheetfile "supply.kicad_sch")
		(attr smd)
		(fp_rect
			(start -0.93 -0.47)
			(end 0.93 0.47)
			(stroke
				(width 0.05)
				(type solid)
			)
			(fill no)
			(layer "F.CrtYd")
		)
		(fp_rect
			(start -0.5 -0.25)
			(end 0.5 0.25)
			(stroke
				(width 0.15)
				(type solid)
			)
			(fill no)
			(layer "F.Fab")
		)
		(pad "1" smd roundrect
			(at -0.485 0 180)
			(size 0.59 0.64)
			(layers "F.Cu" "F.Mask" "F.Paste")
			(roundrect_rratio 0.25)
			(net 55 "Net-(C141-Pad1)")
			(pintype "passive")
		)
		(pad "2" smd roundrect
			(at 0.485 0 180)
			(size 0.59 0.64)
			(layers "F.Cu" "F.Mask" "F.Paste")
			(roundrect_rratio 0.25)
			(net 244 "Net-(R103-Pad2)")
			(pintype "passive")
		)
	)
	(footprint "antmicro-footprints:PowerDI5"
		(layer "F.Cu")
		(at 127.4492 125.7 90)
		(property "Reference" "D11"
			(at -1 3.0508 90)
			(layer "F.SilkS")
			(effects
				(font
					(size 0.7 0.7)
					(thickness 0.15)
				)
				(justify left bottom)
			)
		)
		(property "Value" "PDS760"
			(at 0 3.4 270)
			(layer "F.Fab")
			(effects
				(font
					(size 0.7 0.7)
					(thickness 0.15)
				)
				(justify left bottom)
			)
		)
		(property "Description" "PDS760 Series 60 V 7 A Surface Mount Schottky Barrier Rectifier - PowerDI-5"
			(at 0 0 90)
			(layer "F.Fab")
			(hide yes)
			(effects
				(font
					(size 1.27 1.27)
					(thickness 0.15)
				)
			)
		)
		(property "Author" "Antmicro"
			(at 253.1492 -1.7492 0)
			(layer "F.Fab")
			(hide yes)
			(effects
				(font
					(size 1 1)
					(thickness 0.15)
				)
			)
		)
		(property "License" "Apache-2.0"
			(at 253.1492 -1.7492 0)
			(layer "F.Fab")
			(hide yes)
			(effects
				(font
					(size 1 1)
					(thickness 0.15)
				)
			)
		)
		(property "MPN" "PDS760-13"
			(at 253.1492 -1.7492 0)
			(layer "F.Fab")
			(hide yes)
			(effects
				(font
					(size 1 1)
					(thickness 0.15)
				)
			)
		)
		(property "Manufacturer" "Diodes Incorporated"
			(at 253.1492 -1.7492 0)
			(layer "F.Fab")
			(hide yes)
			(effects
				(font
					(size 1 1)
					(thickness 0.15)
				)
			)
		)
		(sheetname "Supply")
		(sheetfile "supply.kicad_sch")
		(attr smd)
		(fp_line
			(start 2.7 -2)
			(end 2.7 -1.8)
			(stroke
				(width 0.12)
				(type solid)
			)
			(layer "F.SilkS")
		)
		(fp_line
			(start -2.7 -2)
			(end 2.7 -2)
			(stroke
				(width 0.12)
				(type solid)
			)
			(layer "F.SilkS")
		)
		(fp_line
			(start -2.7 -1.8)
			(end -2.7 -2)
			(stroke
				(width 0.12)
				(type solid)
			)
			(layer "F.SilkS")
		)
		(fp_line
			(start 2.7 1.823)
			(end 2.7 2.023)
			(stroke
				(width 0.12)
				(type solid)
			)
			(layer "F.SilkS")
		)
		(fp_line
			(start 2.7 2.023)
			(end -2.7 2.023)
			(stroke
				(width 0.12)
				(type solid)
			)
			(layer "F.SilkS")
		)
		(fp_line
			(start -2.7 2.023)
			(end -2.7 1.823)
			(stroke
				(width 0.12)
				(type solid)
			)
			(layer "F.SilkS")
		)
		(fp_rect
			(start -3.702 -2.3)
			(end 3.7 2.3)
			(stroke
				(width 0.05)
				(type solid)
			)
			(fill no)
			(layer "F.CrtYd")
		)
		(pad "A" smd roundrect
			(at -2.862 -0.94 180)
			(size 1.39 1.4)
			(layers "F.Cu" "F.Mask" "F.Paste")
			(roundrect_rratio 0.25)
			(net 5 "GND")
			(pinfunction "A")
			(pintype "passive")
		)
		(pad "A" smd roundrect
			(at -2.862 0.941)
			(size 1.39 1.4)
			(layers "F.Cu" "F.Mask" "F.Paste")
			(roundrect_rratio 0.25)
			(net 5 "GND")
			(pinfunction "A")
			(pintype "passive")
		)
		(pad "C" smd roundrect
			(at 1.1 0)
			(size 3.36 4.86)
			(layers "F.Cu" "F.Mask" "F.Paste")
			(roundrect_rratio 0.05)
			(net 42 "Net-(IC2-SW)")
			(pinfunction "C")
			(pintype "passive")
		)
	)
)
